(kicad_pcb
	(version 20241229)
	(generator "pcbnew")
	(generator_version "9.0")
	(general
		(thickness 1.599998)
		(legacy_teardrops no)
	)
	(paper "A4")
	(title_block
		(date "2023-02-12")
		(rev "1.1.5")
		(comment 9 "footprints 210-214 of 473")
	)
	(layers
		(0 "F.Cu" signal)
		(4 "In1.Cu" power "In1.GND")
		(6 "In2.Cu" signal)
		(8 "In3.Cu" power "In3.GND")
		(10 "In4.Cu" power "In4.VCC")
		(12 "In5.Cu" signal)
		(14 "In6.Cu" power "In6.VCC")
		(2 "B.Cu" signal)
		(9 "F.Adhes" user "F.Adhesive")
		(11 "B.Adhes" user "B.Adhesive")
		(13 "F.Paste" user)
		(15 "B.Paste" user)
		(5 "F.SilkS" user "F.Silkscreen")
		(7 "B.SilkS" user "B.Silkscreen")
		(1 "F.Mask" user)
		(3 "B.Mask" user)
		(17 "Dwgs.User" user "User.Drawings")
		(19 "Cmts.User" user "User.Comments")
		(21 "Eco1.User" user "User.Eco1")
		(23 "Eco2.User" user "User.Eco2")
		(25 "Edge.Cuts" user)
		(27 "Margin" user)
		(31 "F.CrtYd" user "F.Courtyard")
		(29 "B.CrtYd" user "B.Courtyard")
		(35 "F.Fab" user)
		(33 "B.Fab" user)
	)
	(footprint "antmicro-footprints:V-QFN2030-12"
		(layer "F.Cu")
		(at 126.863672 88.903992 180)
		(property "Reference" "U10"
			(at -0.836328 -2.496008 180)
			(layer "F.SilkS")
			(effects
				(font
					(size 0.7 0.7)
					(thickness 0.15)
				)
				(justify left bottom)
			)
		)
		(property "Value" "AP62600SJ-7"
			(at -4 2.2 180)
			(layer "F.Fab")
			(effects
				(font
					(size 0.7 0.7)
					(thickness 0.15)
				)
				(justify left bottom)
			)
		)
		(property "Description" "Buck Switching Regulator IC Positive Fixed 0.6V 1 Output 6A 12-VFQFN"
			(at 0 0 180)
			(layer "F.Fab")
			(hide yes)
			(effects
				(font
					(size 1.27 1.27)
					(thickness 0.15)
				)
			)
		)
		(property "Author" "Antmicro"
			(at 253.727344 177.807984 0)
			(layer "F.Fab")
			(hide yes)
			(effects
				(font
					(size 1 1)
					(thickness 0.15)
				)
			)
		)
		(property "License" "Apache-2.0"
			(at 253.727344 177.807984 0)
			(layer "F.Fab")
			(hide yes)
			(effects
				(font
					(size 1 1)
					(thickness 0.15)
				)
			)
		)
		(property "MPN" "AP62600SJ-7"
			(at 253.727344 177.807984 0)
			(layer "F.Fab")
			(hide yes)
			(effects
				(font
					(size 1 1)
					(thickness 0.15)
				)
			)
		)
		(property "Manufacturer" "Diodes Incorporated"
			(at 253.727344 177.807984 0)
			(layer "F.Fab")
			(hide yes)
			(effects
				(font
					(size 1 1)
					(thickness 0.15)
				)
			)
		)
		(sheetname "Supply")
		(sheetfile "supply.kicad_sch")
		(attr smd)
		(fp_line
			(start 1.8 1.199)
			(end 0.8 1.199)
			(stroke
				(width 0.15)
				(type solid)
			)
			(layer "F.SilkS")
		)
		(fp_line
			(start 1.8 0.998)
			(end 1.8 1.199)
			(stroke
				(width 0.15)
				(type solid)
			)
			(layer "F.SilkS")
		)
		(fp_line
			(start 1.8 -1.276)
			(end 1.8 -1.025)
			(stroke
				(width 0.15)
				(type solid)
			)
			(layer "F.SilkS")
		)
		(fp_line
			(start -0.802 1.199)
			(end -1.801 1.199)
			(stroke
				(width 0.15)
				(type solid)
			)
			(layer "F.SilkS")
		)
		(fp_line
			(start -1.801 1.199)
			(end -1.801 0.998)
			(stroke
				(width 0.15)
				(type solid)
			)
			(layer "F.SilkS")
		)
		(fp_line
			(start -1.801 -1)
			(end -1.801 -1.2)
			(stroke
				(width 0.15)
				(type solid)
			)
			(layer "F.SilkS")
		)
		(fp_line
			(start -1.801 -1.2)
			(end -0.802 -1.2)
			(stroke
				(width 0.15)
				(type solid)
			)
			(layer "F.SilkS")
		)
		(fp_circle
			(center 0.497 -1.7)
			(end 0.548 -1.7)
			(stroke
				(width 0.15)
				(type solid)
			)
			(fill yes)
			(layer "F.SilkS")
		)
		(fp_rect
			(start -2.026 -1.525)
			(end 2.023 1.524)
			(stroke
				(width 0.05)
				(type solid)
			)
			(fill no)
			(layer "F.CrtYd")
		)
		(fp_line
			(start 1.3 -1)
			(end 1.5 -0.8)
			(stroke
				(width 0.15)
				(type solid)
			)
			(layer "F.Fab")
		)
		(fp_rect
			(start -1.526 -1.025)
			(end 1.523 1.024)
			(stroke
				(width 0.15)
				(type solid)
			)
			(fill no)
			(layer "F.Fab")
		)
		(pad "1" smd rect
			(at 0.498 -0.552 90)
			(size 1.6 0.35)
			(layers "F.Cu" "F.Mask" "F.Paste")
			(net 5 "GND")
			(pinfunction "PGND")
			(pintype "passive")
		)
		(pad "2" smd rect
			(at -0.5 -0.552 90)
			(size 1.6 0.35)
			(layers "F.Cu" "F.Mask" "F.Paste")
			(net 463 "VCC5V0_INT")
			(pinfunction "VIN")
			(pintype "power_in")
		)
		(pad "3" smd rect
			(at -1.45 -0.75 90)
			(size 0.35 0.8)
			(layers "F.Cu" "F.Mask" "F.Paste")
			(net 590 "/Supply/1V1_EN")
			(pinfunction "EN")
			(pintype "input")
		)
		(pad "4" smd rect
			(at -1.45 -0.25 90)
			(size 0.35 0.8)
			(layers "F.Cu" "F.Mask" "F.Paste")
			(net 621 "/Supply/1V1_MODE")
			(pinfunction "MODE")
			(pintype "input")
		)
		(pad "5" smd rect
			(at -1.45 0.248 90)
			(size 0.35 0.8)
			(layers "F.Cu" "F.Mask" "F.Paste")
			(net 615 "/Supply/1V1_FSEL")
			(pinfunction "FSEL")
			(pintype "input")
		)
		(pad "6" smd rect
			(at -1.45 0.748 90)
			(size 0.35 0.8)
			(layers "F.Cu" "F.Mask" "F.Paste")
			(net 654 "unconnected-(U10-PG-Pad6)")
			(pinfunction "PG")
			(pintype "open_collector+no_connect")
		)
		(pad "7" smd rect
			(at -0.5 0.949 180)
			(size 0.35 0.8)
			(layers "F.Cu" "F.Mask" "F.Paste")
			(net 580 "/Supply/1V1_BST")
			(pinfunction "BST")
			(pintype "input")
		)
		(pad "8" smd rect
			(at 0 0.55 90)
			(size 1.6 0.35)
			(layers "F.Cu" "F.Mask" "F.Paste")
			(net 579 "/Supply/1V1_SW")
			(pinfunction "SW")
			(pintype "output")
		)
		(pad "9" smd rect
			(at 1.449 0.748 270)
			(size 0.35 0.8)
			(layers "F.Cu" "F.Mask" "F.Paste")
			(net 591 "/Supply/1V1_VCC_INT")
			(pinfunction "VCC")
			(pintype "input")
		)
		(pad "10" smd rect
			(at 1.449 0.248 270)
			(size 0.35 0.8)
			(layers "F.Cu" "F.Mask" "F.Paste")
			(net 622 "/Supply/1V1_SS{slash}TR")
			(pinfunction "SS/TR")
			(pintype "input")
		)
		(pad "11" smd rect
			(at 1.449 -0.25 270)
			(size 0.35 0.8)
			(layers "F.Cu" "F.Mask" "F.Paste")
			(net 5 "GND")
			(pinfunction "GND")
			(pintype "passive")
		)
		(pad "12" smd rect
			(at 1.449 -0.75 270)
			(size 0.35 0.8)
			(layers "F.Cu" "F.Mask" "F.Paste")
			(net 598 "/Supply/1V1_FB")
			(pinfunction "FB")
			(pintype "input")
		)
	)
	(footprint "antmicro-footprints:R_0402_1005Metric"
		(layer "F.Cu")
		(at 129.95 88.074 180)
		(descr "Resistor SMD 0402")
		(tags "resistor SMD 0402")
		(property "Reference" "R121"
			(at 1.285328 2.474 180)
			(layer "F.SilkS")
			(effects
				(font
					(size 0.7 0.7)
					(thickness 0.15)
				)
				(justify left bottom)
			)
		)
		(property "Value" "R_0R_0402"
			(at 0 1.4 180)
			(layer "F.Fab")
			(effects
				(font
					(size 0.7 0.7)
					(thickness 0.15)
				)
				(justify left bottom)
			)
		)
		(property "Description" "0R resistor in 0402 package with unspecified tolerance"
			(at 0 0 180)
			(layer "F.Fab")
			(hide yes)
			(effects
				(font
					(size 1.27 1.27)
					(thickness 0.15)
				)
			)
		)
		(property "Author" "Antmicro"
			(at 259.9 176.148 0)
			(layer "F.Fab")
			(hide yes)
			(effects
				(font
					(size 1 1)
					(thickness 0.15)
				)
			)
		)
		(property "Current" "1A"
			(at 259.9 176.148 0)
			(layer "F.Fab")
			(hide yes)
			(effects
				(font
					(size 1 1)
					(thickness 0.15)
				)
			)
		)
		(property "License" "Apache-2.0"
			(at 259.9 176.148 0)
			(layer "F.Fab")
			(hide yes)
			(effects
				(font
					(size 1 1)
					(thickness 0.15)
				)
			)
		)
		(property "MPN" "ERJ2GE0R00X"
			(at 259.9 176.148 0)
			(layer "F.Fab")
			(hide yes)
			(effects
				(font
					(size 1 1)
					(thickness 0.15)
				)
			)
		)
		(property "Manufacturer" "Panasonic"
			(at 259.9 176.148 0)
			(layer "F.Fab")
			(hide yes)
			(effects
				(font
					(size 1 1)
					(thickness 0.15)
				)
			)
		)
		(property "Tolerance" ""
			(at 259.9 176.148 0)
			(layer "F.Fab")
			(hide yes)
			(effects
				(font
					(size 1 1)
					(thickness 0.15)
				)
			)
		)
		(property "Val" "0R"
			(at 259.9 176.148 0)
			(layer "F.Fab")
			(hide yes)
			(effects
				(font
					(size 1 1)
					(thickness 0.15)
				)
			)
		)
		(sheetname "Supply")
		(sheetfile "supply.kicad_sch")
		(attr smd)
		(fp_rect
			(start -0.93 -0.47)
			(end 0.93 0.47)
			(stroke
				(width 0.05)
				(type solid)
			)
			(fill no)
			(layer "F.CrtYd")
		)
		(fp_rect
			(start -0.5 -0.25)
			(end 0.5 0.25)
			(stroke
				(width 0.15)
				(type solid)
			)
			(fill no)
			(layer "F.Fab")
		)
		(pad "1" smd roundrect
			(at -0.485 0 180)
			(size 0.59 0.64)
			(layers "F.Cu" "F.Mask" "F.Paste")
			(roundrect_rratio 0.25)
			(net 591 "/Supply/1V1_VCC_INT")
			(pintype "passive")
		)
		(pad "2" smd roundrect
			(at 0.485 0 180)
			(size 0.59 0.64)
			(layers "F.Cu" "F.Mask" "F.Paste")
			(roundrect_rratio 0.25)
			(net 615 "/Supply/1V1_FSEL")
			(pintype "passive")
		)
	)
	(footprint "antmicro-footprints:C_0402_1005Metric"
		(layer "F.Cu")
		(at 111.725 97.249 180)
		(descr "Capacitor SMD 0402")
		(tags "capacitor SMD 0402")
		(property "Reference" "C172"
			(at 3.625 -0.351 180)
			(layer "F.SilkS")
			(effects
				(font
					(size 0.7 0.7)
					(thickness 0.15)
				)
				(justify left bottom)
			)
		)
		(property "Value" "C_22u_0402"
			(at 0 1.4 180)
			(layer "F.Fab")
			(effects
				(font
					(size 0.7 0.7)
					(thickness 0.15)
				)
				(justify left bottom)
			)
		)
		(property "Description" " "
			(at 0 0 180)
			(layer "F.Fab")
			(hide yes)
			(effects
				(font
					(size 1.27 1.27)
					(thickness 0.15)
				)
			)
		)
		(property "Author" "Antmicro"
			(at 223.45 194.498 0)
			(layer "F.Fab")
			(hide yes)
			(effects
				(font
					(size 1 1)
					(thickness 0.15)
				)
			)
		)
		(property "Dielectric" ""
			(at 223.45 194.498 0)
			(layer "F.Fab")
			(hide yes)
			(effects
				(font
					(size 1 1)
					(thickness 0.15)
				)
			)
		)
		(property "License" "Apache-2.0"
			(at 223.45 194.498 0)
			(layer "F.Fab")
			(hide yes)
			(effects
				(font
					(size 1 1)
					(thickness 0.15)
				)
			)
		)
		(property "MPN" "04024W226MAT2A"
			(at 223.45 194.498 0)
			(layer "F.Fab")
			(hide yes)
			(effects
				(font
					(size 1 1)
					(thickness 0.15)
				)
			)
		)
		(property "Manufacturer" "AVX"
			(at 223.45 194.498 0)
			(layer "F.Fab")
			(hide yes)
			(effects
				(font
					(size 1 1)
					(thickness 0.15)
				)
			)
		)
		(property "Val" "22u"
			(at 223.45 194.498 0)
			(layer "F.Fab")
			(hide yes)
			(effects
				(font
					(size 1 1)
					(thickness 0.15)
				)
			)
		)
		(property "Voltage" ""
			(at 223.45 194.498 0)
			(layer "F.Fab")
			(hide yes)
			(effects
				(font
					(size 1 1)
					(thickness 0.15)
				)
			)
		)
		(sheetname "Supply")
		(sheetfile "supply.kicad_sch")
		(attr smd)
		(fp_rect
			(start -0.94 -0.47)
			(end 0.94 0.47)
			(stroke
				(width 0.05)
				(type solid)
			)
			(fill no)
			(layer "F.CrtYd")
		)
		(fp_rect
			(start -0.499 -0.249)
			(end 0.499 0.249)
			(stroke
				(width 0.15)
				(type solid)
			)
			(fill no)
			(layer "F.Fab")
		)
		(pad "1" smd roundrect
			(at -0.484 0 180)
			(size 0.59 0.64)
			(layers "F.Cu" "F.Mask" "F.Paste")
			(roundrect_rratio 0.25)
			(net 576 "/Supply/3V3_REG")
			(pintype "passive")
		)
		(pad "2" smd roundrect
			(at 0.484 0 180)
			(size 0.59 0.64)
			(layers "F.Cu" "F.Mask" "F.Paste")
			(roundrect_rratio 0.25)
			(net 5 "GND")
			(pintype "passive")
		)
	)
	(footprint "antmicro-footprints:Vishay_PowerPAK_1212-8_Single"
		(layer "F.Cu")
		(at 110.9992 122.4 180)
		(descr "PowerPAK 1212-8 Single (https://www.vishay.com/docs/71656/ppak12128.pdf, https://www.vishay.com/docs/72597/72597.pdf)")
		(tags "Vishay PowerPAK 1212-8 Single")
		(property "Reference" "Q12"
			(at 0.0992 1.9 0)
			(layer "F.SilkS")
			(effects
				(font
					(size 0.7 0.7)
					(thickness 0.15)
				)
				(justify left bottom)
			)
		)
		(property "Value" "SQS401EN-T1_BE3"
			(at -8 2.7 180)
			(layer "F.Fab")
			(effects
				(font
					(size 0.7 0.7)
					(thickness 0.15)
				)
				(justify left bottom)
			)
		)
		(property "Description" "MOSFET P-CHANNEL 40V (D-S), 16 A, PowerPAK 1212-8 Single"
			(at 0 0 180)
			(layer "F.Fab")
			(hide yes)
			(effects
				(font
					(size 1.27 1.27)
					(thickness 0.15)
				)
			)
		)
		(property "Author" "Antmicro"
			(at 221.9984 244.8 0)
			(layer "F.Fab")
			(hide yes)
			(effects
				(font
					(size 1 1)
					(thickness 0.15)
				)
			)
		)
		(property "License" "Apache-2.0"
			(at 221.9984 244.8 0)
			(layer "F.Fab")
			(hide yes)
			(effects
				(font
					(size 1 1)
					(thickness 0.15)
				)
			)
		)
		(property "MPN" "SQS401EN-T1_BE3"
			(at 221.9984 244.8 0)
			(layer "F.Fab")
			(hide yes)
			(effects
				(font
					(size 1 1)
					(thickness 0.15)
				)
			)
		)
		(property "Manufacturer" "Vishay"
			(at 221.9984 244.8 0)
			(layer "F.Fab")
			(hide yes)
			(effects
				(font
					(size 1 1)
					(thickness 0.15)
				)
			)
		)
		(sheetname "Supply")
		(sheetfile "supply.kicad_sch")
		(attr smd)
		(fp_line
			(start 1.634 1.3)
			(end 1.634 1.634)
			(stroke
				(width 0.15)
				(type solid)
			)
			(layer "F.SilkS")
		)
		(fp_line
			(start 1.634 -1.635)
			(end 1.634 -1.301)
			(stroke
				(width 0.15)
				(type solid)
			)
			(layer "F.SilkS")
		)
		(fp_line
			(start -1.635 1.634)
			(end 1.634 1.634)
			(stroke
				(width 0.15)
				(type solid)
			)
			(layer "F.SilkS")
		)
		(fp_line
			(start -1.635 1.3)
			(end -1.635 1.634)
			(stroke
				(width 0.15)
				(type solid)
			)
			(layer "F.SilkS")
		)
		(fp_line
			(start -1.871 -1.635)
			(end 1.634 -1.635)
			(stroke
				(width 0.15)
				(type solid)
			)
			(layer "F.SilkS")
		)
		(fp_circle
			(center -2.451 -0.99)
			(end -2.401 -0.99)
			(stroke
				(width 0.15)
				(type solid)
			)
			(fill yes)
			(layer "F.SilkS")
		)
		(fp_rect
			(start -2.151 -2.151)
			(end 2.148 2.148)
			(stroke
				(width 0.05)
				(type solid)
			)
			(fill no)
			(layer "F.CrtYd")
		)
		(fp_line
			(start -1.6425 -1.4175)
			(end -1.4175 -1.6425)
			(stroke
				(width 0.15)
				(type solid)
			)
			(layer "F.Fab")
		)
		(fp_rect
			(start -1.651 -1.651)
			(end 1.648 1.648)
			(stroke
				(width 0.15)
				(type solid)
			)
			(fill no)
			(layer "F.Fab")
		)
		(pad "1" smd rect
			(at -1.436 -0.99 180)
			(size 0.99 0.405)
			(layers "F.Cu" "F.Mask" "F.Paste")
			(net 76 "Net-(J6-Pad1)")
			(pinfunction "S")
			(pintype "bidirectional")
		)
		(pad "2" smd rect
			(at -1.436 -0.332 180)
			(size 0.99 0.405)
			(layers "F.Cu" "F.Mask" "F.Paste")
			(net 76 "Net-(J6-Pad1)")
			(pinfunction "S")
			(pintype "bidirectional")
		)
		(pad "3" smd rect
			(at -1.436 0.33 180)
			(size 0.99 0.405)
			(layers "F.Cu" "F.Mask" "F.Paste")
			(net 76 "Net-(J6-Pad1)")
			(pinfunction "S")
			(pintype "bidirectional")
		)
		(pad "4" smd rect
			(at -1.436 0.988 180)
			(size 0.99 0.405)
			(layers "F.Cu" "F.Mask" "F.Paste")
			(net 5 "GND")
			(pinfunction "G")
			(pintype "bidirectional")
		)
		(pad "5" smd custom
			(at 0.557 0 180)
			(size 1.725 2.235)
			(layers "F.Cu" "F.Mask" "F.Paste")
			(net 224 "VIN")
			(pinfunction "D")
			(pintype "bidirectional")
			(zone_connect 2)
			(options
				(clearance outline)
				(anchor rect)
			)
			(primitives
				(gr_poly
					(pts
						(xy 0.8625 0.1275) (xy 0.8625 -0.1275) (xy 1.3725 -0.1275) (xy 1.3725 -0.5325) (xy 0.8625 -0.5325)
						(xy 0.8625 -0.7875) (xy 1.3725 -0.7875) (xy 1.3725 -1.195) (xy 0.6125 -1.195) (xy 0.6125 1.195)
						(xy 1.3725 1.195) (xy 1.3725 0.7875) (xy 0.8625 0.7875) (xy 0.8625 0.5325) (xy 1.3725 0.5325)
						(xy 1.3725 0.1275)
					)
					(width 0)
					(fill yes)
				)
			)
		)
	)
	(footprint "antmicro-footprints:C_0402_1005Metric"
		(layer "F.Cu")
		(at 125.675 52.1 180)
		(descr "Capacitor SMD 0402")
		(tags "capacitor SMD 0402")
		(property "Reference" "C194"
			(at 1.175 1.5 180)
			(layer "F.SilkS")
			(effects
				(font
					(size 0.7 0.7)
					(thickness 0.15)
				)
				(justify left bottom)
			)
		)
		(property "Value" "C_10u_0402"
			(at 0 1.4 180)
			(layer "F.Fab")
			(effects
				(font
					(size 0.7 0.7)
					(thickness 0.15)
				)
				(justify left bottom)
			)
		)
		(property "Description" " "
			(at 0 0 180)
			(layer "F.Fab")
			(hide yes)
			(effects
				(font
					(size 1.27 1.27)
					(thickness 0.15)
				)
			)
		)
		(property "Author" "Antmicro"
			(at 251.35 104.2 0)
			(layer "F.Fab")
			(hide yes)
			(effects
				(font
					(size 1 1)
					(thickness 0.15)
				)
			)
		)
		(property "Dielectric" ""
			(at 251.35 104.2 0)
			(layer "F.Fab")
			(hide yes)
			(effects
				(font
					(size 1 1)
					(thickness 0.15)
				)
			)
		)
		(property "License" "Apache-2.0"
			(at 251.35 104.2 0)
			(layer "F.Fab")
			(hide yes)
			(effects
				(font
					(size 1 1)
					(thickness 0.15)
				)
			)
		)
		(property "MPN" "CC0402MRX5R5BB106"
			(at 251.35 104.2 0)
			(layer "F.Fab")
			(hide yes)
			(effects
				(font
					(size 1 1)
					(thickness 0.15)
				)
			)
		)
		(property "Manufacturer" "Yaego"
			(at 251.35 104.2 0)
			(layer "F.Fab")
			(hide yes)
			(effects
				(font
					(size 1 1)
					(thickness 0.15)
				)
			)
		)
		(property "Val" "10u"
			(at 251.35 104.2 0)
			(layer "F.Fab")
			(hide yes)
			(effects
				(font
					(size 1 1)
					(thickness 0.15)
				)
			)
		)
		(property "Voltage" ""
			(at 251.35 104.2 0)
			(layer "F.Fab")
			(hide yes)
			(effects
				(font
					(size 1 1)
					(thickness 0.15)
				)
			)
		)
		(sheetname "Supply")
		(sheetfile "supply.kicad_sch")
		(attr exclude_from_pos_files exclude_from_bom dnp)
		(fp_rect
			(start -0.94 -0.47)
			(end 0.94 0.47)
			(stroke
				(width 0.05)
				(type solid)
			)
			(fill no)
			(layer "F.CrtYd")
		)
		(fp_rect
			(start -0.499 -0.249)
			(end 0.499 0.249)
			(stroke
				(width 0.15)
				(type solid)
			)
			(fill no)
			(layer "F.Fab")
		)
		(pad "1" smd roundrect
			(at -0.484 0 180)
			(size 0.59 0.64)
			(layers "F.Cu" "F.Mask" "F.Paste")
			(roundrect_rratio 0.25)
			(net 627 "/Supply/VDDQ_0V6")
			(pintype "passive")
		)
		(pad "2" smd roundrect
			(at 0.484 0 180)
			(size 0.59 0.64)
			(layers "F.Cu" "F.Mask" "F.Paste")
			(roundrect_rratio 0.25)
			(net 5 "GND")
			(pintype "passive")
		)
	)
)
